# T6G (Grand Teton) — schematic netlist excerpt (pin names and nets, part order shuffled) for the footprints in the layout excerpt that follows; sources: Cadence DE-HDL packaged netlist, KiCad conversion of 04192023_DAF0TMB3IC0_F0TG_MB_C_brd_V02_OCP.brd

J99  SCONN288_DDR506112002KQ  IO  pkg DDR288S_1-1VXC  page 108
  VIN_BULK0  = P12V_MEM_CPU1
  RFU0  = NC
  VIN_MGMT  = P3V3_AUX
  HSCL  = I3C_SPD_DDRK_CPU1_SCL
  HSDA  = I3C_SPD_DDRK_CPU1_SDA
  VSS0  = GND
  DQ0_A  = M_K_CPU1_SA_DQ<0>
  VSS1  = GND
  DQ1_A  = M_K_CPU1_SA_DQ<1>
  VSS2  = GND
  DQS0_A_T  = M_K_CPU1_SA_DQS_DP<0>
  DQS0_A_C  = M_K_CPU1_SA_DQS_DN<0>
  VSS3  = GND
  DQ4_A  = M_K_CPU1_SA_DQ<4>
  VSS4  = GND
  DQ5_A  = M_K_CPU1_SA_DQ<5>
  VSS5  = GND
  DQ8_A  = M_K_CPU1_SA_DQ<8>
  VSS6  = GND
  DQ9_A  = M_K_CPU1_SA_DQ<9>
  VSS7  = GND
  DQS1_A_T  = M_K_CPU1_SA_DQS_DP<1>
  DQS1_A_C  = M_K_CPU1_SA_DQS_DN<1>
  VSS8  = GND
  DQ12_A  = M_K_CPU1_SA_DQ<12>
  VSS9  = GND
  DQ13_A  = M_K_CPU1_SA_DQ<13>
  VSS10  = GND
  DQ16_A  = M_K_CPU1_SA_DQ<16>
  VSS11  = GND
  DQ17_A  = M_K_CPU1_SA_DQ<17>
  VSS12  = GND
  DQS2_A_T  = M_K_CPU1_SA_DQS_DP<2>
  DQS2_A_C  = M_K_CPU1_SA_DQS_DN<2>
  VSS13  = GND
  DQ20_A  = M_K_CPU1_SA_DQ<20>
  VSS14  = GND
  DQ21_A  = M_K_CPU1_SA_DQ<21>
  VSS15  = GND
  DQ24_A  = M_K_CPU1_SA_DQ<24>
  VSS16  = GND
  DQ25_A  = M_K_CPU1_SA_DQ<25>
  VSS17  = GND
  DQS3_A_T  = M_K_CPU1_SA_DQS_DP<3>
  DQS3_A_C  = M_K_CPU1_SA_DQS_DN<3>
  VSS18  = GND
  DQ28_A  = M_K_CPU1_SA_DQ<28>
  VSS19  = GND
  DQ29_A  = M_K_CPU1_SA_DQ<29>
  VSS20  = GND
  CB0_A  = M_K_CPU1_SA_CB<0>
  VSS21  = GND
  CB1_A  = M_K_CPU1_SA_CB<1>
  VSS22  = GND
  DQS4_A_T  = M_K_CPU1_SA_DQS_DP<4>
  DQS4_A_C  = M_K_CPU1_SA_DQS_DN<4>
  VSS23  = GND
  CB4_A  = M_K_CPU1_SA_CB<4>
  VSS24  = GND
  CB5_A  = M_K_CPU1_SA_CB<5>
  VSS25  = GND
  ALERT_N  = M_K_CPU1_ALERT_N
  VSS26  = GND
  CS0_A_N  = M_K_CPU1_SA_CS_N<0>
  VSS27  = GND
  CA0_A  = M_K_CPU1_SA_CA<0>
  VSS28  = GND
  CA2_A  = M_K_CPU1_SA_CA<2>
  VSS29  = GND
  CA4_A  = M_K_CPU1_SA_CA<4>
  VSS30  = GND
  CA6_A  = M_K_CPU1_SA_CA<6>
  VSS31  = GND
  PAR_A  = M_K_CPU1_SA_PAR
  VSS32  = GND
  CA0_B  = M_K_CPU1_SB_CA<0>
  VSS33  = GND
  CA2_B  = M_K_CPU1_SB_CA<2>
  VSS34  = GND
  CA4_B  = M_K_CPU1_SB_CA<4>
  VSS35  = GND
  CA6_B  = M_K_CPU1_SB_CA<6>
  VSS36  = GND
  CS0_B_N  = M_K_CPU1_SB_CS_N<0>
  VSS37  = GND
  \lbd||rsp_a_n\  = M_K_CPU1_SA_RSP<0>
  \lbs||rsp_b_n\  = M_K_CPU1_SB_RSP<0>
  VSS38  = GND
  CB4_B  = M_K_CPU1_SB_CB<4>
  VSS39  = GND
  CB5_B  = M_K_CPU1_SB_CB<5>
  VSS40  = GND
  \dqs9_b_t||tdqs9_b_t||dbi4_b_n\  = M_K_CPU1_SB_DQS_DP<9>
  \dqs9_b_c||tdqs9_b_c\  = M_K_CPU1_SB_DQS_DN<9>
  VSS41  = GND
  CB0_B  = M_K_CPU1_SB_CB<0>
  VSS42  = GND
  CB1_B  = M_K_CPU1_SB_CB<1>
  VSS43  = GND
  DQ0_B  = M_K_CPU1_SB_DQ<0>
  VSS44  = GND
  DQ1_B  = M_K_CPU1_SB_DQ<1>
  VSS45  = GND
  DQS0_B_T  = M_K_CPU1_SB_DQS_DP<0>
  DQS0_B_C  = M_K_CPU1_SB_DQS_DN<0>
  VSS46  = GND
  DQ4_B  = M_K_CPU1_SB_DQ<4>
  VSS47  = GND
  DQ5_B  = M_K_CPU1_SB_DQ<5>
  VSS48  = GND
  DQ8_B  = M_K_CPU1_SB_DQ<8>
  VSS49  = GND
  DQ9_B  = M_K_CPU1_SB_DQ<9>
  VSS50  = GND
  DQS1_B_T  = M_K_CPU1_SB_DQS_DP<1>
  DQS1_B_C  = M_K_CPU1_SB_DQS_DN<1>
  VSS51  = GND
  DQ12_B  = M_K_CPU1_SB_DQ<12>
  VSS52  = GND
  DQ13_B  = M_K_CPU1_SB_DQ<13>
  VSS53  = GND
  DQ16_B  = M_K_CPU1_SB_DQ<16>
  VSS54  = GND
  DQ17_B  = M_K_CPU1_SB_DQ<17>
  VSS55  = GND
  DQS2_B_T  = M_K_CPU1_SB_DQS_DP<2>
  DQS2_B_C  = M_K_CPU1_SB_DQS_DN<2>
  VSS56  = GND
  DQ20_B  = M_K_CPU1_SB_DQ<20>
  VSS57  = GND
  DQ21_B  = M_K_CPU1_SB_DQ<21>
  VSS58  = GND
  DQ24_B  = M_K_CPU1_SB_DQ<24>
  VSS59  = GND
  DQ25_B  = M_K_CPU1_SB_DQ<25>
  VSS60  = GND
  DQS3_B_T  = M_K_CPU1_SB_DQS_DP<3>
  DQS3_B_C  = M_K_CPU1_SB_DQS_DN<3>
  VSS61  = GND
  DQ28_B  = M_K_CPU1_SB_DQ<28>
  VSS62  = GND
  DQ29_B  = M_K_CPU1_SB_DQ<29>
  VSS63  = GND
  RFU1  = NC
  VIN_BULK1  = P12V_MEM_CPU1
  VIN_BULK2  = P12V_MEM_CPU1
  \pwr_good||fail_n\  = PWRGD_CHK_CPU1_DIMM
  HAS  = PD_CHK_CPU1_DIMM_SAA
  RFU2  = NC
  RFU3  = NC
  VSS64  = GND
  DQ2_A  = M_K_CPU1_SA_DQ<2>
  VSS65  = GND
  DQ3_A  = M_K_CPU1_SA_DQ<3>
  VSS66  = GND
  \dqs5_a_c||tdqs5_a_c||dqs5_a_t||tdqs5_a_t\  = M_K_CPU1_SA_DQS_DN<5>
  \dqs5_a_t||tdqs5_a_t\  = M_K_CPU1_SA_DQS_DP<5>
  VSS67  = GND
  DQ6_A  = M_K_CPU1_SA_DQ<6>
  VSS68  = GND
  DQ7_A  = M_K_CPU1_SA_DQ<7>
  VSS69  = GND
  DQ10_A  = M_K_CPU1_SA_DQ<10>
  VSS70  = GND
  DQ11_A  = M_K_CPU1_SA_DQ<11>
  VSS71  = GND
  \dqs6_a_c||tdqs6_a_c||dqs6_a_t||tdqs6_a_t\  = M_K_CPU1_SA_DQS_DN<6>
  \dqs6_a_t||tdqs6_a_t\  = M_K_CPU1_SA_DQS_DP<6>
  VSS72  = GND
  DQ14_A  = M_K_CPU1_SA_DQ<14>
  VSS73  = GND
  DQ15_A  = M_K_CPU1_SA_DQ<15>
  VSS74  = GND
  DQ18_A  = M_K_CPU1_SA_DQ<18>
  VSS75  = GND
  DQ19_A  = M_K_CPU1_SA_DQ<19>
  VSS76  = GND
  \dqs7_a_c||tdqs7_a_c\  = M_K_CPU1_SA_DQS_DN<7>
  \dqs7_a_t||tdqs7_a_t\  = M_K_CPU1_SA_DQS_DP<7>
  VSS77  = GND
  DQ22_A  = M_K_CPU1_SA_DQ<22>
  VSS78  = GND
  DQ23_A  = M_K_CPU1_SA_DQ<23>
  VSS79  = GND
  DQ26_A  = M_K_CPU1_SA_DQ<26>
  VSS80  = GND
  DQ27_A  = M_K_CPU1_SA_DQ<27>
  VSS81  = GND
  \dqs8_a_c||tdqs8_a_c\  = M_K_CPU1_SA_DQS_DN<8>
  \dqs8_a_t||tdqs8_a_t\  = M_K_CPU1_SA_DQS_DP<8>
  VSS82  = GND
  DQ30_A  = M_K_CPU1_SA_DQ<30>
  VSS83  = GND
  DQ31_A  = M_K_CPU1_SA_DQ<31>
  VSS84  = GND
  CB2_A  = M_K_CPU1_SA_CB<2>
  VSS85  = GND
  CB3_A  = M_K_CPU1_SA_CB<3>
  VSS86  = GND
  \dqs9_a_c||tdqs9_a_c\  = M_K_CPU1_SA_DQS_DN<9>
  \dqs9_a_t||tdqs9_a_t\  = M_K_CPU1_SA_DQS_DP<9>
  VSS87  = GND
  CB6_A  = M_K_CPU1_SA_CB<6>
  VSS88  = GND
  CB7_A  = M_K_CPU1_SA_CB<7>
  VSS89  = GND
  RESET_N  = M_K_CPU1_RESET_N
  VSS90  = GND
  CS1_A_N  = M_K_CPU1_SA_CS_N<1>
  VSS91  = GND
  CA1_A  = M_K_CPU1_SA_CA<1>
  VSS92  = GND
  CA3_A  = M_K_CPU1_SA_CA<3>
  VSS93  = GND
  CA5_A  = M_K_CPU1_SA_CA<5>
  VSS94  = GND
  CK_T  = M_K_CPU1_CLK_DP<0>
  CK_C  = M_K_CPU1_CLK_DN<0>
  VSS95  = GND
  RFU4  = NC
  CA1_B  = M_K_CPU1_SB_CA<1>
  VSS96  = GND
  CA3_B  = M_K_CPU1_SB_CA<3>
  VSS97  = GND
  CA5_B  = M_K_CPU1_SB_CA<5>
  VSS98  = GND
  PAR_B  = M_K_CPU1_SB_PAR
  VSS99  = GND
  CS1_B_N  = M_K_CPU1_SB_CS_N<1>
  VSS100  = GND
  RFU5  = NC
  RFU6  = NC
  VSS101  = GND
  CB6_B  = M_K_CPU1_SB_CB<6>
  VSS102  = GND
  CB7_B  = M_K_CPU1_SB_CB<7>
  VSS103  = GND
  DQS4_B_C  = M_K_CPU1_SB_DQS_DN<4>
  DQS4_B_T  = M_K_CPU1_SB_DQS_DP<4>
  VSS104  = GND
  CB2_B  = M_K_CPU1_SB_CB<2>
  VSS105  = GND
  CB3_B  = M_K_CPU1_SB_CB<3>
  VSS106  = GND
  DQ2_B  = M_K_CPU1_SB_DQ<2>
  VSS107  = GND
  DQ3_B  = M_K_CPU1_SB_DQ<3>
  VSS108  = GND
  \dqs5_b_c||tdqs5_b_c\  = M_K_CPU1_SB_DQS_DN<5>
  \dqs5_b_t||tdqs5_b_t\  = M_K_CPU1_SB_DQS_DP<5>
  VSS109  = GND
  DQ6_B  = M_K_CPU1_SB_DQ<6>
  VSS110  = GND
  DQ7_B  = M_K_CPU1_SB_DQ<7>
  VSS111  = GND
  DQ10_B  = M_K_CPU1_SB_DQ<10>
  VSS112  = GND
  DQ11_B  = M_K_CPU1_SB_DQ<11>
  VSS113  = GND
  \dqs6_b_c||tdqs6_b_c\  = M_K_CPU1_SB_DQS_DN<6>
  \dqs6_b_t||tdqs6_b_t\  = M_K_CPU1_SB_DQS_DP<6>
  VSS114  = GND
  DQ14_B  = M_K_CPU1_SB_DQ<14>
  VSS115  = GND
  DQ15_B  = M_K_CPU1_SB_DQ<15>
  VSS116  = GND
  DQ18_B  = M_K_CPU1_SB_DQ<18>
  VSS117  = GND
  DQ19_B  = M_K_CPU1_SB_DQ<19>
  VSS118  = GND
  \dqs7_b_c||tdqs7_b_c\  = M_K_CPU1_SB_DQS_DN<7>
  \dqs7_b_t||tdqs7_b_t\  = M_K_CPU1_SB_DQS_DP<7>
  VSS119  = GND
  DQ22_B  = M_K_CPU1_SB_DQ<22>
  VSS120  = GND
  DQ23_B  = M_K_CPU1_SB_DQ<23>
  VSS121  = GND
  DQ26_B  = M_K_CPU1_SB_DQ<26>
  VSS122  = GND
  DQ27_B  = M_K_CPU1_SB_DQ<27>
  VSS123  = GND
  \dqs8_b_c||tdqs8_b_c\  = M_K_CPU1_SB_DQS_DN<8>
  \dqs8_b_t||tdqs8_b_t\  = M_K_CPU1_SB_DQS_DP<8>
  VSS124  = GND
  DQ30_B  = M_K_CPU1_SB_DQ<30>
  VSS125  = GND
  DQ31_B  = M_K_CPU1_SB_DQ<31>
  VSS126  = GND
  G1  = GND
  G2  = GND
  G3  = GND

(kicad_pcb
	(version 20260206)
	(generator "pcbnew")
	(generator_version "10.0")
	(general
		(thickness 1.6)
		(legacy_teardrops no)
	)
	(paper "A4")
	(title_block
		(title "04192023_DAF0TMB3IC0_F0TG_MB_C_brd_V02_OCP.brd")
		(comment 1 "Grand Teton / footprint 4555 of 8354 (J99), pads 231-276 of 291")
	)
	(layers
		(0 "F.Cu" signal "TOP")
		(4 "In1.Cu" signal "GND")
		(6 "In2.Cu" signal "IN1")
		(8 "In3.Cu" signal "GND1")
		(10 "In4.Cu" signal "IN2")
		(12 "In5.Cu" signal "GND2")
		(14 "In6.Cu" signal "IN3")
		(16 "In7.Cu" signal "GND3")
		(18 "In8.Cu" signal "VCC")
		(20 "In9.Cu" signal "VCC1")
		(22 "In10.Cu" signal "GND4")
		(24 "In11.Cu" signal "IN4")
		(26 "In12.Cu" signal "GND5")
		(28 "In13.Cu" signal "IN5")
		(30 "In14.Cu" signal "GND6")
		(32 "In15.Cu" signal "IN6")
		(34 "In16.Cu" signal "GND7")
		(2 "B.Cu" signal "BOTTOM")
		(9 "F.Adhes" user "F.Adhesive")
		(11 "B.Adhes" user "B.Adhesive")
		(13 "F.Paste" user "Package Geometry/Pastemask Top")
		(15 "B.Paste" user "Package Geometry/Pastemask Bottom")
		(5 "F.SilkS" user "Ref Des/Silkscreen Top")
		(7 "B.SilkS" user "Ref Des/Silkscreen Bottom")
		(1 "F.Mask" user "Board Geometry/Soldermask Top")
		(3 "B.Mask" user "Board Geometry/Soldermask Bottom")
		(17 "Dwgs.User" user "User.Drawings")
		(19 "Cmts.User" user "User.Comments")
		(21 "Eco1.User" user "User.Eco1")
		(23 "Eco2.User" user "User.Eco2")
		(25 "Edge.Cuts" user "Board Geometry/Outline")
		(27 "Margin" user)
		(31 "F.CrtYd" user "Package Geometry/Place Bound Top")
		(29 "B.CrtYd" user "Package Geometry/Place Bound Bottom")
		(35 "F.Fab" user "Ref Des/Assembly Top")
		(33 "B.Fab" user "Ref Des/Assembly Bottom")
	)
	(footprint ""
		(layer "F.Cu")
		(at 196.654166 -255.560322 180)
		(property "Reference" "J99"
			(at -0.4318 -81.730088 0)
			(unlocked yes)
			(layer "F.SilkS")
			(effects
				(font
					(size 0.7874 0.5842)
					(thickness 0.1524)
				)
			)
		)
		(property "Value" ""
			(at 0 0 180)
			(layer "F.Fab")
			(effects
				(font
					(size 1.27 1.27)
				)
			)
		)
		(duplicate_pad_numbers_are_jumpers no)
		(pad "231" smd rect
			(at 2.050034 14.875002 90)
			(size 0.519938 1.4986)
			(layers "F.Cu" "F.Mask" "F.Paste")
			(net "Net_2401")
		)
		(pad "232" smd rect
			(at 2.050034 15.724886 90)
			(size 0.519938 1.4986)
			(layers "F.Cu" "F.Mask" "F.Paste")
			(net "Net_2402")
		)
		(pad "233" smd rect
			(at 2.050034 16.575024 90)
			(size 0.519938 1.4986)
			(layers "F.Cu" "F.Mask" "F.Paste")
			(net "GND")
		)
		(pad "234" smd rect
			(at 2.050034 17.424908 90)
			(size 0.519938 1.4986)
			(layers "F.Cu" "F.Mask" "F.Paste")
			(net "M_K_CPU1_SB_CB<6>")
		)
		(pad "235" smd rect
			(at 2.050034 18.275046 90)
			(size 0.519938 1.4986)
			(layers "F.Cu" "F.Mask" "F.Paste")
			(net "GND")
		)
		(pad "236" smd rect
			(at 2.050034 19.12493 90)
			(size 0.519938 1.4986)
			(layers "F.Cu" "F.Mask" "F.Paste")
			(net "M_K_CPU1_SB_CB<7>")
		)
		(pad "237" smd rect
			(at 2.050034 19.975068 90)
			(size 0.519938 1.4986)
			(layers "F.Cu" "F.Mask" "F.Paste")
			(net "GND")
		)
		(pad "238" smd rect
			(at 2.050034 20.824952 90)
			(size 0.519938 1.4986)
			(layers "F.Cu" "F.Mask" "F.Paste")
			(net "M_K_CPU1_SB_DQS_DN<4>")
		)
		(pad "239" smd rect
			(at 2.050034 21.67509 90)
			(size 0.519938 1.4986)
			(layers "F.Cu" "F.Mask" "F.Paste")
			(net "M_K_CPU1_SB_DQS_DP<4>")
		)
		(pad "240" smd rect
			(at 2.050034 22.524974 90)
			(size 0.519938 1.4986)
			(layers "F.Cu" "F.Mask" "F.Paste")
			(net "GND")
		)
		(pad "241" smd rect
			(at 2.050034 23.375112 90)
			(size 0.519938 1.4986)
			(layers "F.Cu" "F.Mask" "F.Paste")
			(net "M_K_CPU1_SB_CB<2>")
		)
		(pad "242" smd rect
			(at 2.050034 24.224996 90)
			(size 0.519938 1.4986)
			(layers "F.Cu" "F.Mask" "F.Paste")
			(net "GND")
		)
		(pad "243" smd rect
			(at 2.050034 25.07488 90)
			(size 0.519938 1.4986)
			(layers "F.Cu" "F.Mask" "F.Paste")
			(net "M_K_CPU1_SB_CB<3>")
		)
		(pad "244" smd rect
			(at 2.050034 25.925018 90)
			(size 0.519938 1.4986)
			(layers "F.Cu" "F.Mask" "F.Paste")
			(net "GND")
		)
		(pad "245" smd rect
			(at 2.050034 26.774902 90)
			(size 0.519938 1.4986)
			(layers "F.Cu" "F.Mask" "F.Paste")
			(net "M_K_CPU1_SB_DQ<2>")
		)
		(pad "246" smd rect
			(at 2.050034 27.62504 90)
			(size 0.519938 1.4986)
			(layers "F.Cu" "F.Mask" "F.Paste")
			(net "GND")
		)
		(pad "247" smd rect
			(at 2.050034 28.474924 90)
			(size 0.519938 1.4986)
			(layers "F.Cu" "F.Mask" "F.Paste")
			(net "M_K_CPU1_SB_DQ<3>")
		)
		(pad "248" smd rect
			(at 2.050034 29.325062 90)
			(size 0.519938 1.4986)
			(layers "F.Cu" "F.Mask" "F.Paste")
			(net "GND")
		)
		(pad "249" smd rect
			(at 2.050034 30.174946 90)
			(size 0.519938 1.4986)
			(layers "F.Cu" "F.Mask" "F.Paste")
			(net "M_K_CPU1_SB_DQS_DN<5>")
		)
		(pad "250" smd rect
			(at 2.050034 31.025084 90)
			(size 0.519938 1.4986)
			(layers "F.Cu" "F.Mask" "F.Paste")
			(net "M_K_CPU1_SB_DQS_DP<5>")
		)
		(pad "251" smd rect
			(at 2.050034 31.874968 90)
			(size 0.519938 1.4986)
			(layers "F.Cu" "F.Mask" "F.Paste")
			(net "GND")
		)
		(pad "252" smd rect
			(at 2.050034 32.725106 90)
			(size 0.519938 1.4986)
			(layers "F.Cu" "F.Mask" "F.Paste")
			(net "M_K_CPU1_SB_DQ<6>")
		)
		(pad "253" smd rect
			(at 2.050034 33.57499 90)
			(size 0.519938 1.4986)
			(layers "F.Cu" "F.Mask" "F.Paste")
			(net "GND")
		)
		(pad "254" smd rect
			(at 2.050034 34.425128 90)
			(size 0.519938 1.4986)
			(layers "F.Cu" "F.Mask" "F.Paste")
			(net "M_K_CPU1_SB_DQ<7>")
		)
		(pad "255" smd rect
			(at 2.050034 35.275012 90)
			(size 0.519938 1.4986)
			(layers "F.Cu" "F.Mask" "F.Paste")
			(net "GND")
		)
		(pad "256" smd rect
			(at 2.050034 36.124896 90)
			(size 0.519938 1.4986)
			(layers "F.Cu" "F.Mask" "F.Paste")
			(net "M_K_CPU1_SB_DQ<10>")
		)
		(pad "257" smd rect
			(at 2.050034 36.975034 90)
			(size 0.519938 1.4986)
			(layers "F.Cu" "F.Mask" "F.Paste")
			(net "GND")
		)
		(pad "258" smd rect
			(at 2.050034 37.824918 90)
			(size 0.519938 1.4986)
			(layers "F.Cu" "F.Mask" "F.Paste")
			(net "M_K_CPU1_SB_DQ<11>")
		)
		(pad "259" smd rect
			(at 2.050034 38.675056 90)
			(size 0.519938 1.4986)
			(layers "F.Cu" "F.Mask" "F.Paste")
			(net "GND")
		)
		(pad "260" smd rect
			(at 2.050034 39.52494 90)
			(size 0.519938 1.4986)
			(layers "F.Cu" "F.Mask" "F.Paste")
			(net "M_K_CPU1_SB_DQS_DN<6>")
		)
		(pad "261" smd rect
			(at 2.050034 40.375078 90)
			(size 0.519938 1.4986)
			(layers "F.Cu" "F.Mask" "F.Paste")
			(net "M_K_CPU1_SB_DQS_DP<6>")
		)
		(pad "262" smd rect
			(at 2.050034 41.224962 90)
			(size 0.519938 1.4986)
			(layers "F.Cu" "F.Mask" "F.Paste")
			(net "GND")
		)
		(pad "263" smd rect
			(at 2.050034 42.0751 90)
			(size 0.519938 1.4986)
			(layers "F.Cu" "F.Mask" "F.Paste")
			(net "M_K_CPU1_SB_DQ<14>")
		)
		(pad "264" smd rect
			(at 2.050034 42.924984 90)
			(size 0.519938 1.4986)
			(layers "F.Cu" "F.Mask" "F.Paste")
			(net "GND")
		)
		(pad "265" smd rect
			(at 2.050034 43.775122 90)
			(size 0.519938 1.4986)
			(layers "F.Cu" "F.Mask" "F.Paste")
			(net "M_K_CPU1_SB_DQ<15>")
		)
		(pad "266" smd rect
			(at 2.050034 44.625006 90)
			(size 0.519938 1.4986)
			(layers "F.Cu" "F.Mask" "F.Paste")
			(net "GND")
		)
		(pad "267" smd rect
			(at 2.050034 45.47489 90)
			(size 0.519938 1.4986)
			(layers "F.Cu" "F.Mask" "F.Paste")
			(net "M_K_CPU1_SB_DQ<18>")
		)
		(pad "268" smd rect
			(at 2.050034 46.325028 90)
			(size 0.519938 1.4986)
			(layers "F.Cu" "F.Mask" "F.Paste")
			(net "GND")
		)
		(pad "269" smd rect
			(at 2.050034 47.174912 90)
			(size 0.519938 1.4986)
			(layers "F.Cu" "F.Mask" "F.Paste")
			(net "M_K_CPU1_SB_DQ<19>")
		)
		(pad "270" smd rect
			(at 2.050034 48.02505 90)
			(size 0.519938 1.4986)
			(layers "F.Cu" "F.Mask" "F.Paste")
			(net "GND")
		)
		(pad "271" smd rect
			(at 2.050034 48.874934 90)
			(size 0.519938 1.4986)
			(layers "F.Cu" "F.Mask" "F.Paste")
			(net "M_K_CPU1_SB_DQS_DN<7>")
		)
		(pad "272" smd rect
			(at 2.050034 49.725072 90)
			(size 0.519938 1.4986)
			(layers "F.Cu" "F.Mask" "F.Paste")
			(net "M_K_CPU1_SB_DQS_DP<7>")
		)
		(pad "273" smd rect
			(at 2.050034 50.574956 90)
			(size 0.519938 1.4986)
			(layers "F.Cu" "F.Mask" "F.Paste")
			(net "GND")
		)
		(pad "274" smd rect
			(at 2.050034 51.425094 90)
			(size 0.519938 1.4986)
			(layers "F.Cu" "F.Mask" "F.Paste")
			(net "M_K_CPU1_SB_DQ<22>")
		)
		(pad "275" smd rect
			(at 2.050034 52.274978 90)
			(size 0.519938 1.4986)
			(layers "F.Cu" "F.Mask" "F.Paste")
			(net "GND")
		)
		(pad "276" smd rect
			(at 2.050034 53.125116 90)
			(size 0.519938 1.4986)
			(layers "F.Cu" "F.Mask" "F.Paste")
			(net "M_K_CPU1_SB_DQ<23>")
		)
	)
)
